#ISCELL
  pure_quanta quanta_title_block_c *
  *
#CELL
  pure_quanta socket4677_azif0045p001c01cs *
  page18_i1
